(kicad_pcb
	(version 20260206)
	(generator "pcbnew")
	(generator_version "10.0")
	(general
		(thickness 1.6)
		(legacy_teardrops no)
	)
	(paper "A4")
	(title_block
		(title "Wiwynn_Tioga_Pass_MB.brd")
		(comment 1 "Tioga Pass / footprints 3122-3129 of 4770")
	)
	(layers
		(0 "F.Cu" signal "TOP")
		(4 "In1.Cu" signal "L2GND")
		(6 "In2.Cu" signal "L3")
		(8 "In3.Cu" signal "L4GND")
		(10 "In4.Cu" signal "L5")
		(12 "In5.Cu" signal "L6GND")
		(14 "In6.Cu" signal "L7VCC")
		(16 "In7.Cu" signal "L8VCC")
		(18 "In8.Cu" signal "L9GND")
		(20 "In9.Cu" signal "L10")
		(22 "In10.Cu" signal "L11GND")
		(24 "In11.Cu" signal "L12")
		(26 "In12.Cu" signal "L13GND")
		(2 "B.Cu" signal "BOTTOM")
		(9 "F.Adhes" user "F.Adhesive")
		(11 "B.Adhes" user "B.Adhesive")
		(13 "F.Paste" user "Package Geometry/Pastemask Top")
		(15 "B.Paste" user "Package Geometry/Pastemask Bottom")
		(5 "F.SilkS" user "Ref Des/Silkscreen Top")
		(7 "B.SilkS" user "Ref Des/Silkscreen Bottom")
		(1 "F.Mask" user "Board Geometry/Soldermask Top")
		(3 "B.Mask" user "Board Geometry/Soldermask Bottom")
		(17 "Dwgs.User" user "User.Drawings")
		(19 "Cmts.User" user "User.Comments")
		(21 "Eco1.User" user "User.Eco1")
		(23 "Eco2.User" user "User.Eco2")
		(25 "Edge.Cuts" user "Board Geometry/Outline")
		(27 "Margin" user)
		(31 "F.CrtYd" user "Package Geometry/Place Bound Top")
		(29 "B.CrtYd" user "Package Geometry/Place Bound Bottom")
		(35 "F.Fab" user "Ref Des/Assembly Top")
		(33 "B.Fab" user "Ref Des/Assembly Bottom")
	)
	(footprint ""
		(layer "B.Cu")
		(at 261.7978 -157.0228 -90)
		(property "Reference" "C5L5"
			(at -1.47828 0.78994 0)
			(unlocked yes)
			(layer "B.SilkS")
			(effects
				(font
					(size 0.4064 0.254)
					(thickness 0.1524)
				)
				(justify mirror)
			)
		)
		(property "Value" ""
			(at 0 0 90)
			(layer "B.Fab")
			(effects
				(font
					(size 1.27 1.27)
				)
				(justify mirror)
			)
		)
		(duplicate_pad_numbers_are_jumpers no)
		(fp_poly
			(pts
				(xy 0.7239 -0.2159) (xy -0.7239 -0.2159) (xy -0.7239 1.9939) (xy 0.7239 1.9939)
			)
			(stroke
				(width 0)
				(type default)
			)
			(fill no)
			(layer "B.CrtYd")
		)
		(fp_line
			(start -0.7239 1.9939)
			(end -0.7239 -0.2159)
			(stroke
				(width 0.1)
				(type default)
			)
			(layer "B.Fab")
		)
		(fp_line
			(start 0.7239 1.9939)
			(end -0.7239 1.9939)
			(stroke
				(width 0.1)
				(type default)
			)
			(layer "B.Fab")
		)
		(fp_line
			(start -0.7239 -0.2159)
			(end 0.7239 -0.2159)
			(stroke
				(width 0.1)
				(type default)
			)
			(layer "B.Fab")
		)
		(fp_line
			(start 0.7239 -0.2159)
			(end 0.7239 1.9939)
			(stroke
				(width 0.1)
				(type default)
			)
			(layer "B.Fab")
		)
		(pad "1" smd rect
			(at 0 0 90)
			(size 1.27 1.016)
			(layers "B.Cu" "B.Mask" "B.Paste")
			(net "PVTT_DEF")
		)
		(pad "2" smd rect
			(at 0 1.778 90)
			(size 1.27 1.016)
			(layers "B.Cu" "B.Mask" "B.Paste")
			(net "GND")
		)
		(zone
			(layer "B.Cu")
			(hatch none 0.5)
			(connect_pads
				(clearance 0)
			)
			(min_thickness 0.25)
			(keepout
				(tracks not_allowed)
				(vias allowed)
				(pads allowed)
				(copperpour not_allowed)
				(footprints allowed)
			)
			(placement
				(enabled no)
				(sheetname "")
			)
			(fill
				(thermal_gap 0.5)
				(thermal_bridge_width 0.5)
				(island_removal_mode 0)
			)
			(polygon
				(pts
					(xy 261.2898 -156.3878) (xy 261.2898 -157.6578) (xy 260.5278 -157.6578) (xy 260.5278 -156.3878)
				)
			)
		)
	)
	(footprint ""
		(layer "B.Cu")
		(at 390.635744 -21.679916 -90)
		(property "Reference" "C2T29"
			(at 0 0 90)
			(layer "B.SilkS")
			(hide yes)
			(effects
				(font
					(size 1.27 1.27)
				)
				(justify mirror)
			)
		)
		(property "Value" ""
			(at 0 0 90)
			(layer "B.Fab")
			(effects
				(font
					(size 1.27 1.27)
				)
				(justify mirror)
			)
		)
		(duplicate_pad_numbers_are_jumpers no)
		(fp_poly
			(pts
				(xy -0.3048 -0.1016) (xy -0.3048 0.9906) (xy 0.3048 0.9906) (xy 0.3048 -0.1016)
			)
			(stroke
				(width 0)
				(type default)
			)
			(fill no)
			(layer "B.CrtYd")
		)
		(fp_line
			(start -0.3048 0.9906)
			(end -0.3048 -0.1016)
			(stroke
				(width 0.1)
				(type default)
			)
			(layer "B.Fab")
		)
		(fp_line
			(start 0.3048 0.9906)
			(end -0.3048 0.9906)
			(stroke
				(width 0.1)
				(type default)
			)
			(layer "B.Fab")
		)
		(fp_line
			(start -0.3048 -0.1016)
			(end 0.3048 -0.1016)
			(stroke
				(width 0.1)
				(type default)
			)
			(layer "B.Fab")
		)
		(fp_line
			(start 0.3048 -0.1016)
			(end 0.3048 0.9906)
			(stroke
				(width 0.1)
				(type default)
			)
			(layer "B.Fab")
		)
		(pad "1" smd rect
			(at 0 0 90)
			(size 0.508 0.508)
			(layers "B.Cu" "B.Mask" "B.Paste")
			(net "P3V3")
		)
		(pad "2" smd rect
			(at 0 0.889 90)
			(size 0.508 0.508)
			(layers "B.Cu" "B.Mask" "B.Paste")
			(net "GND")
		)
		(zone
			(layer "B.Cu")
			(hatch none 0.5)
			(connect_pads
				(clearance 0)
			)
			(min_thickness 0.25)
			(keepout
				(tracks not_allowed)
				(vias allowed)
				(pads allowed)
				(copperpour not_allowed)
				(footprints allowed)
			)
			(placement
				(enabled no)
				(sheetname "")
			)
			(fill
				(thermal_gap 0.5)
				(thermal_bridge_width 0.5)
				(island_removal_mode 0)
			)
			(polygon
				(pts
					(xy 390.000744 -21.425916) (xy 390.000744 -21.933916) (xy 390.381744 -21.933916) (xy 390.381744 -21.425916)
				)
			)
		)
		(zone
			(layer "B.Cu")
			(hatch none 0.5)
			(connect_pads
				(clearance 0)
			)
			(min_thickness 0.25)
			(keepout
				(tracks allowed)
				(vias not_allowed)
				(pads allowed)
				(copperpour not_allowed)
				(footprints allowed)
			)
			(placement
				(enabled no)
				(sheetname "")
			)
			(fill
				(thermal_gap 0.5)
				(thermal_bridge_width 0.5)
				(island_removal_mode 0)
			)
			(polygon
				(pts
					(xy 390.381744 -21.425916) (xy 390.381744 -21.933916) (xy 390.000744 -21.933916) (xy 390.000744 -21.425916)
				)
			)
		)
	)
	(footprint ""
		(layer "B.Cu")
		(at 185.039 -72.898)
		(property "Reference" "R6P27"
			(at 0 0 0)
			(layer "B.SilkS")
			(hide yes)
			(effects
				(font
					(size 1.27 1.27)
				)
				(justify mirror)
			)
		)
		(property "Value" ""
			(at 0 0 0)
			(layer "B.Fab")
			(effects
				(font
					(size 1.27 1.27)
				)
				(justify mirror)
			)
		)
		(duplicate_pad_numbers_are_jumpers no)
		(fp_rect
			(start -0.2794 0.9906)
			(end 0.2794 -0.1016)
			(stroke
				(width 0)
				(type default)
			)
			(fill no)
			(layer "B.CrtYd")
		)
		(fp_line
			(start -0.2794 -0.1016)
			(end 0.2794 -0.1016)
			(stroke
				(width 0.1)
				(type default)
			)
			(layer "B.Fab")
		)
		(fp_line
			(start -0.2794 0.9906)
			(end -0.2794 -0.1016)
			(stroke
				(width 0.1)
				(type default)
			)
			(layer "B.Fab")
		)
		(fp_line
			(start 0.2794 -0.1016)
			(end 0.2794 0.9906)
			(stroke
				(width 0.1)
				(type default)
			)
			(layer "B.Fab")
		)
		(fp_line
			(start 0.2794 0.9906)
			(end -0.2794 0.9906)
			(stroke
				(width 0.1)
				(type default)
			)
			(layer "B.Fab")
		)
		(pad "1" smd rect
			(at 0 0 180)
			(size 0.508 0.508)
			(layers "B.Cu" "B.Mask" "B.Paste")
			(net "VR_PVCCIN_CPU0_XADDR2")
		)
		(pad "2" smd rect
			(at 0 0.889 180)
			(size 0.508 0.508)
			(layers "B.Cu" "B.Mask" "B.Paste")
			(net "GND")
		)
		(zone
			(layer "B.Cu")
			(hatch none 0.5)
			(connect_pads
				(clearance 0)
			)
			(min_thickness 0.25)
			(keepout
				(tracks not_allowed)
				(vias allowed)
				(pads allowed)
				(copperpour not_allowed)
				(footprints allowed)
			)
			(placement
				(enabled no)
				(sheetname "")
			)
			(fill
				(thermal_gap 0.5)
				(thermal_bridge_width 0.5)
				(island_removal_mode 0)
			)
			(polygon
				(pts
					(xy 184.785 -72.263) (xy 185.293 -72.263) (xy 185.293 -72.644) (xy 184.785 -72.644)
				)
			)
		)
		(zone
			(layer "B.Cu")
			(hatch none 0.5)
			(connect_pads
				(clearance 0)
			)
			(min_thickness 0.25)
			(keepout
				(tracks allowed)
				(vias not_allowed)
				(pads allowed)
				(copperpour not_allowed)
				(footprints allowed)
			)
			(placement
				(enabled no)
				(sheetname "")
			)
			(fill
				(thermal_gap 0.5)
				(thermal_bridge_width 0.5)
				(island_removal_mode 0)
			)
			(polygon
				(pts
					(xy 184.785 -72.263) (xy 185.293 -72.263) (xy 185.293 -72.644) (xy 184.785 -72.644)
				)
			)
		)
	)
	(footprint ""
		(layer "B.Cu")
		(at 405.2062 -105.8545 180)
		(property "Reference" "C2N22"
			(at 0 0 0)
			(layer "B.SilkS")
			(hide yes)
			(effects
				(font
					(size 1.27 1.27)
				)
				(justify mirror)
			)
		)
		(property "Value" ""
			(at 0 0 0)
			(layer "B.Fab")
			(effects
				(font
					(size 1.27 1.27)
				)
				(justify mirror)
			)
		)
		(duplicate_pad_numbers_are_jumpers no)
		(fp_poly
			(pts
				(xy 0.4953 -0.2032) (xy -0.4953 -0.2032) (xy -0.4953 1.6002) (xy 0.4953 1.6002)
			)
			(stroke
				(width 0)
				(type default)
			)
			(fill no)
			(layer "B.CrtYd")
		)
		(fp_line
			(start 0.4953 1.6002)
			(end 0.4953 -0.2032)
			(stroke
				(width 0.1)
				(type default)
			)
			(layer "B.Fab")
		)
		(fp_line
			(start 0.4953 -0.2032)
			(end -0.4953 -0.2032)
			(stroke
				(width 0.1)
				(type default)
			)
			(layer "B.Fab")
		)
		(fp_line
			(start -0.4953 1.6002)
			(end 0.4953 1.6002)
			(stroke
				(width 0.1)
				(type default)
			)
			(layer "B.Fab")
		)
		(fp_line
			(start -0.4953 -0.2032)
			(end -0.4953 1.6002)
			(stroke
				(width 0.1)
				(type default)
			)
			(layer "B.Fab")
		)
		(pad "1" smd rect
			(at 0 0)
			(size 0.762 0.889)
			(layers "B.Cu" "B.Mask" "B.Paste")
			(net "P3V3_STBY")
		)
		(pad "2" smd rect
			(at 0 1.397)
			(size 0.762 0.889)
			(layers "B.Cu" "B.Mask" "B.Paste")
			(net "GND")
		)
		(zone
			(layer "B.Cu")
			(hatch none 0.5)
			(connect_pads
				(clearance 0)
			)
			(min_thickness 0.25)
			(keepout
				(tracks not_allowed)
				(vias allowed)
				(pads allowed)
				(copperpour not_allowed)
				(footprints allowed)
			)
			(placement
				(enabled no)
				(sheetname "")
			)
			(fill
				(thermal_gap 0.5)
				(thermal_bridge_width 0.5)
				(island_removal_mode 0)
			)
			(polygon
				(pts
					(xy 404.8252 -106.299) (xy 405.5872 -106.299) (xy 405.5872 -106.807) (xy 404.8252 -106.807)
				)
			)
		)
	)
	(footprint ""
		(layer "B.Cu")
		(at 408.432 -119.391684)
		(property "Reference" "C2M10"
			(at 0 0 0)
			(layer "B.SilkS")
			(hide yes)
			(effects
				(font
					(size 1.27 1.27)
				)
				(justify mirror)
			)
		)
		(property "Value" ""
			(at 0 0 0)
			(layer "B.Fab")
			(effects
				(font
					(size 1.27 1.27)
				)
				(justify mirror)
			)
		)
		(duplicate_pad_numbers_are_jumpers no)
		(fp_poly
			(pts
				(xy 0.4953 -0.2032) (xy -0.4953 -0.2032) (xy -0.4953 1.6002) (xy 0.4953 1.6002)
			)
			(stroke
				(width 0)
				(type default)
			)
			(fill no)
			(layer "B.CrtYd")
		)
		(fp_line
			(start -0.4953 -0.2032)
			(end -0.4953 1.6002)
			(stroke
				(width 0.1)
				(type default)
			)
			(layer "B.Fab")
		)
		(fp_line
			(start -0.4953 1.6002)
			(end 0.4953 1.6002)
			(stroke
				(width 0.1)
				(type default)
			)
			(layer "B.Fab")
		)
		(fp_line
			(start 0.4953 -0.2032)
			(end -0.4953 -0.2032)
			(stroke
				(width 0.1)
				(type default)
			)
			(layer "B.Fab")
		)
		(fp_line
			(start 0.4953 1.6002)
			(end 0.4953 -0.2032)
			(stroke
				(width 0.1)
				(type default)
			)
			(layer "B.Fab")
		)
		(pad "1" smd rect
			(at 0 0 180)
			(size 0.762 0.889)
			(layers "B.Cu" "B.Mask" "B.Paste")
			(net "P1V05_PCH_STBY_WM26_PLL")
		)
		(pad "2" smd rect
			(at 0 1.397 180)
			(size 0.762 0.889)
			(layers "B.Cu" "B.Mask" "B.Paste")
			(net "GND")
		)
		(zone
			(layer "B.Cu")
			(hatch none 0.5)
			(connect_pads
				(clearance 0)
			)
			(min_thickness 0.25)
			(keepout
				(tracks not_allowed)
				(vias allowed)
				(pads allowed)
				(copperpour not_allowed)
				(footprints allowed)
			)
			(placement
				(enabled no)
				(sheetname "")
			)
			(fill
				(thermal_gap 0.5)
				(thermal_bridge_width 0.5)
				(island_removal_mode 0)
			)
			(polygon
				(pts
					(xy 408.813 -118.947184) (xy 408.051 -118.947184) (xy 408.051 -118.439184) (xy 408.813 -118.439184)
				)
			)
		)
	)
	(footprint ""
		(layer "B.Cu")
		(at 451.030594 -17.9451 -90)
		(property "Reference" "R3W2"
			(at 0.8382 -0.67818 270)
			(unlocked yes)
			(layer "B.SilkS")
			(effects
				(font
					(size 0.4064 0.254)
					(thickness 0.1524)
				)
				(justify left mirror)
			)
		)
		(property "Value" ""
			(at 0 0 90)
			(layer "B.Fab")
			(effects
				(font
					(size 1.27 1.27)
				)
				(justify mirror)
			)
		)
		(duplicate_pad_numbers_are_jumpers no)
		(fp_poly
			(pts
				(xy 0.2794 -0.1016) (xy -0.2794 -0.1016) (xy -0.2794 0.9906) (xy 0.2794 0.9906)
			)
			(stroke
				(width 0)
				(type default)
			)
			(fill no)
			(layer "B.CrtYd")
		)
		(fp_line
			(start -0.2794 0.9906)
			(end -0.2794 -0.1016)
			(stroke
				(width 0.1)
				(type default)
			)
			(layer "B.Fab")
		)
		(fp_line
			(start 0.2794 0.9906)
			(end -0.2794 0.9906)
			(stroke
				(width 0.1)
				(type default)
			)
			(layer "B.Fab")
		)
		(fp_line
			(start -0.2794 -0.1016)
			(end 0.2794 -0.1016)
			(stroke
				(width 0.1)
				(type default)
			)
			(layer "B.Fab")
		)
		(fp_line
			(start 0.2794 -0.1016)
			(end 0.2794 0.9906)
			(stroke
				(width 0.1)
				(type default)
			)
			(layer "B.Fab")
		)
		(pad "1" smd rect
			(at 0 0 90)
			(size 0.508 0.508)
			(layers "B.Cu" "B.Mask" "B.Paste")
			(net "BMC_TPM_HW_C_RST")
		)
		(pad "2" smd rect
			(at 0 0.889 90)
			(size 0.508 0.508)
			(layers "B.Cu" "B.Mask" "B.Paste")
			(net "GND")
		)
		(zone
			(layer "B.Cu")
			(hatch none 0.5)
			(connect_pads
				(clearance 0)
			)
			(min_thickness 0.25)
			(keepout
				(tracks not_allowed)
				(vias allowed)
				(pads allowed)
				(copperpour not_allowed)
				(footprints allowed)
			)
			(placement
				(enabled no)
				(sheetname "")
			)
			(fill
				(thermal_gap 0.5)
				(thermal_bridge_width 0.5)
				(island_removal_mode 0)
			)
			(polygon
				(pts
					(xy 450.395594 -17.6911) (xy 450.395594 -18.1991) (xy 450.776594 -18.1991) (xy 450.776594 -17.6911)
				)
			)
		)
		(zone
			(layer "B.Cu")
			(hatch none 0.5)
			(connect_pads
				(clearance 0)
			)
			(min_thickness 0.25)
			(keepout
				(tracks allowed)
				(vias not_allowed)
				(pads allowed)
				(copperpour not_allowed)
				(footprints allowed)
			)
			(placement
				(enabled no)
				(sheetname "")
			)
			(fill
				(thermal_gap 0.5)
				(thermal_bridge_width 0.5)
				(island_removal_mode 0)
			)
			(polygon
				(pts
					(xy 450.776594 -17.6911) (xy 450.776594 -18.1991) (xy 450.395594 -18.1991) (xy 450.395594 -17.6911)
				)
			)
		)
	)
	(footprint ""
		(layer "B.Cu")
		(at 460.9846 -35.7124 -90)
		(property "Reference" "R1U21"
			(at 0 0 90)
			(layer "B.SilkS")
			(hide yes)
			(effects
				(font
					(size 1.27 1.27)
				)
				(justify mirror)
			)
		)
		(property "Value" ""
			(at 0 0 90)
			(layer "B.Fab")
			(effects
				(font
					(size 1.27 1.27)
				)
				(justify mirror)
			)
		)
		(duplicate_pad_numbers_are_jumpers no)
		(fp_poly
			(pts
				(xy 0.2794 -0.1016) (xy -0.2794 -0.1016) (xy -0.2794 0.9906) (xy 0.2794 0.9906)
			)
			(stroke
				(width 0)
				(type default)
			)
			(fill no)
			(layer "B.CrtYd")
		)
		(fp_line
			(start -0.2794 0.9906)
			(end -0.2794 -0.1016)
			(stroke
				(width 0.1)
				(type default)
			)
			(layer "B.Fab")
		)
		(fp_line
			(start 0.2794 0.9906)
			(end -0.2794 0.9906)
			(stroke
				(width 0.1)
				(type default)
			)
			(layer "B.Fab")
		)
		(fp_line
			(start -0.2794 -0.1016)
			(end 0.2794 -0.1016)
			(stroke
				(width 0.1)
				(type default)
			)
			(layer "B.Fab")
		)
		(fp_line
			(start 0.2794 -0.1016)
			(end 0.2794 0.9906)
			(stroke
				(width 0.1)
				(type default)
			)
			(layer "B.Fab")
		)
		(pad "1" smd rect
			(at 0 0 90)
			(size 0.508 0.508)
			(layers "B.Cu" "B.Mask" "B.Paste")
			(net "P3V3_STBY")
		)
		(pad "2" smd rect
			(at 0 0.889 90)
			(size 0.508 0.508)
			(layers "B.Cu" "B.Mask" "B.Paste")
			(net "FM_BOARD_SKU_ID3")
		)
		(zone
			(layer "B.Cu")
			(hatch none 0.5)
			(connect_pads
				(clearance 0)
			)
			(min_thickness 0.25)
			(keepout
				(tracks not_allowed)
				(vias allowed)
				(pads allowed)
				(copperpour not_allowed)
				(footprints allowed)
			)
			(placement
				(enabled no)
				(sheetname "")
			)
			(fill
				(thermal_gap 0.5)
				(thermal_bridge_width 0.5)
				(island_removal_mode 0)
			)
			(polygon
				(pts
					(xy 460.3496 -35.4584) (xy 460.3496 -35.9664) (xy 460.7306 -35.9664) (xy 460.7306 -35.4584)
				)
			)
		)
		(zone
			(layer "B.Cu")
			(hatch none 0.5)
			(connect_pads
				(clearance 0)
			)
			(min_thickness 0.25)
			(keepout
				(tracks allowed)
				(vias not_allowed)
				(pads allowed)
				(copperpour not_allowed)
				(footprints allowed)
			)
			(placement
				(enabled no)
				(sheetname "")
			)
			(fill
				(thermal_gap 0.5)
				(thermal_bridge_width 0.5)
				(island_removal_mode 0)
			)
			(polygon
				(pts
					(xy 460.7306 -35.4584) (xy 460.7306 -35.9664) (xy 460.3496 -35.9664) (xy 460.3496 -35.4584)
				)
			)
		)
	)
	(footprint ""
		(layer "B.Cu")
		(at 245.14302 -86.57336 -90)
		(property "Reference" "R5P3"
			(at 0 0 90)
			(layer "B.SilkS")
			(hide yes)
			(effects
				(font
					(size 1.27 1.27)
				)
				(justify mirror)
			)
		)
		(property "Value" ""
			(at 0 0 90)
			(layer "B.Fab")
			(effects
				(font
					(size 1.27 1.27)
				)
				(justify mirror)
			)
		)
		(duplicate_pad_numbers_are_jumpers no)
		(fp_poly
			(pts
				(xy 0.2794 -0.1016) (xy -0.2794 -0.1016) (xy -0.2794 0.9906) (xy 0.2794 0.9906)
			)
			(stroke
				(width 0)
				(type default)
			)
			(fill no)
			(layer "B.CrtYd")
		)
		(fp_line
			(start -0.2794 0.9906)
			(end -0.2794 -0.1016)
			(stroke
				(width 0.1)
				(type default)
			)
			(layer "B.Fab")
		)
		(fp_line
			(start 0.2794 0.9906)
			(end -0.2794 0.9906)
			(stroke
				(width 0.1)
				(type default)
			)
			(layer "B.Fab")
		)
		(fp_line
			(start -0.2794 -0.1016)
			(end 0.2794 -0.1016)
			(stroke
				(width 0.1)
				(type default)
			)
			(layer "B.Fab")
		)
		(fp_line
			(start 0.2794 -0.1016)
			(end 0.2794 0.9906)
			(stroke
				(width 0.1)
				(type default)
			)
			(layer "B.Fab")
		)
		(pad "1" smd rect
			(at 0 0 90)
			(size 0.508 0.508)
			(layers "B.Cu" "B.Mask" "B.Paste")
			(net "PD_CPU0_TEST13")
		)
		(pad "2" smd rect
			(at 0 0.889 90)
			(size 0.508 0.508)
			(layers "B.Cu" "B.Mask" "B.Paste")
			(net "GND")
		)
		(zone
			(layer "B.Cu")
			(hatch none 0.5)
			(connect_pads
				(clearance 0)
			)
			(min_thickness 0.25)
			(keepout
				(tracks not_allowed)
				(vias allowed)
				(pads allowed)
				(copperpour not_allowed)
				(footprints allowed)
			)
			(placement
				(enabled no)
				(sheetname "")
			)
			(fill
				(thermal_gap 0.5)
				(thermal_bridge_width 0.5)
				(island_removal_mode 0)
			)
			(polygon
				(pts
					(xy 244.50802 -86.31936) (xy 244.50802 -86.82736) (xy 244.88902 -86.82736) (xy 244.88902 -86.31936)
				)
			)
		)
		(zone
			(layer "B.Cu")
			(hatch none 0.5)
			(connect_pads
				(clearance 0)
			)
			(min_thickness 0.25)
			(keepout
				(tracks allowed)
				(vias not_allowed)
				(pads allowed)
				(copperpour not_allowed)
				(footprints allowed)
			)
			(placement
				(enabled no)
				(sheetname "")
			)
			(fill
				(thermal_gap 0.5)
				(thermal_bridge_width 0.5)
				(island_removal_mode 0)
			)
			(polygon
				(pts
					(xy 244.88902 -86.31936) (xy 244.88902 -86.82736) (xy 244.50802 -86.82736) (xy 244.50802 -86.31936)
				)
			)
		)
	)
)
